(kicad_sch
	(version 20231120)
	(generator "eeschema")
	(generator_version "8.0")
	(paper "A3")
	(title_block
		(title "GSML Serializer ")
		(date "2024-11-27")
		(rev "1.1.1")
		(company "Antmicro Ltd")
		(comment 1 "www.antmicro.com")
	)
	(junction
		(at 27.94 240.03)
		(diameter 0)
		(color 0 0 0 0)
	)
	(junction
		(at 27.94 226.06)
		(diameter 0)
		(color 0 0 0 0)
	)
	(junction
		(at 27.94 232.41)
		(diameter 0)
		(color 0 0 0 0)
	)
	(wire
		(pts
			(xy 234.95 184.15) (xy 232.41 184.15)
		)
		(stroke
			(width 0)
			(type default)
		)
	)
	(wire
		(pts
			(xy 234.95 200.66) (xy 234.95 184.15)
		)
		(stroke
			(width 0)
			(type default)
		)
	)
	(wire
		(pts
			(xy 232.41 200.66) (xy 234.95 200.66)
		)
		(stroke
			(width 0)
			(type default)
		)
	)
	(wire
		(pts
			(xy 31.75 218.44) (xy 27.94 218.44)
		)
		(stroke
			(width 0)
			(type default)
		)
	)
	(wire
		(pts
			(xy 27.94 240.03) (xy 27.94 243.84)
		)
		(stroke
			(width 0)
			(type default)
		)
	)
	(wire
		(pts
			(xy 31.75 226.06) (xy 27.94 226.06)
		)
		(stroke
			(width 0)
			(type default)
		)
	)
	(bus
		(pts
			(xy 191.77 173.99) (xy 208.28 173.99)
		)
		(stroke
			(width 0)
			(type default)
		)
	)
	(wire
		(pts
			(xy 27.94 218.44) (xy 27.94 226.06)
		)
		(stroke
			(width 0)
			(type default)
		)
	)
	(wire
		(pts
			(xy 232.41 173.99) (xy 250.19 173.99)
		)
		(stroke
			(width 0)
			(type default)
		)
	)
	(wire
		(pts
			(xy 191.77 181.61) (xy 208.28 181.61)
		)
		(stroke
			(width 0)
			(type default)
		)
	)
	(wire
		(pts
			(xy 27.94 226.06) (xy 27.94 232.41)
		)
		(stroke
			(width 0)
			(type default)
		)
	)
	(bus
		(pts
			(xy 191.77 176.53) (xy 208.28 176.53)
		)
		(stroke
			(width 0)
			(type default)
		)
	)
	(wire
		(pts
			(xy 31.75 240.03) (xy 27.94 240.03)
		)
		(stroke
			(width 0)
			(type default)
		)
	)
	(wire
		(pts
			(xy 31.75 232.41) (xy 27.94 232.41)
		)
		(stroke
			(width 0)
			(type default)
		)
	)
	(wire
		(pts
			(xy 191.77 179.07) (xy 208.28 179.07)
		)
		(stroke
			(width 0)
			(type default)
		)
	)
	(wire
		(pts
			(xy 27.94 232.41) (xy 27.94 240.03)
		)
		(stroke
			(width 0)
			(type default)
		)
	)
	(symbol
		(lib_id "antmicroMechanicalParts:MP_Pad6mm_Drill3mm")
		(at 31.75 240.03 0)
		(unit 1)
		(exclude_from_sim no)
		(in_bom no)
		(on_board yes)
		(dnp no)
		(fields_autoplaced yes)
		(property "Reference" "MP4"
			(at 40.64 238.7599 0)
			(effects
				(font
					(size 1.27 1.27)
					(thickness 0.15)
				)
				(justify left)
			)
		)
		(property "Value" "MP_Pad6mm_Drill3mm"
			(at 40.64 241.2999 0)
			(effects
				(font
					(size 1.27 1.27)
					(thickness 0.15)
				)
				(justify left)
			)
		)
		(property "Footprint" "antmicro-footprints:MP_Pad6mm_Drill3mm"
			(at 52.07 247.65 0)
			(effects
				(font
					(size 1.27 1.27)
					(thickness 0.15)
				)
				(justify left bottom)
				(hide yes)
			)
		)
		(property "Datasheet" ""
			(at 48.59 255.6 0)
			(effects
				(font
					(size 1.27 1.27)
					(thickness 0.15)
				)
				(justify left bottom)
				(hide yes)
			)
		)
		(property "Description" ""
			(at 31.75 240.03 0)
			(effects
				(font
					(size 1.27 1.27)
				)
				(hide yes)
			)
		)
		(property "Author" "Antmicro"
			(at 52.07 250.19 0)
			(effects
				(font
					(size 1.27 1.27)
					(thickness 0.15)
				)
				(justify left bottom)
				(hide yes)
			)
		)
		(property "License" "Apache-2.0"
			(at 52.07 252.73 0)
			(effects
				(font
					(size 1.27 1.27)
					(thickness 0.15)
				)
				(justify left bottom)
				(hide yes)
			)
		)
		(pin "1"
		)
		(instances
			(project "gmsl-serializer"
				(path ""
					(reference "MP4")
					(unit 1)
				)
			)
		)
	)
	(symbol
		(lib_id "antmicroMechanicalParts:MP_Pad6mm_Drill3mm")
		(at 31.75 218.44 0)
		(unit 1)
		(exclude_from_sim no)
		(in_bom no)
		(on_board yes)
		(dnp no)
		(fields_autoplaced yes)
		(property "Reference" "MP1"
			(at 40.64 217.1699 0)
			(effects
				(font
					(size 1.27 1.27)
					(thickness 0.15)
				)
				(justify left)
			)
		)
		(property "Value" "MP_Pad6mm_Drill3mm"
			(at 40.64 219.7099 0)
			(effects
				(font
					(size 1.27 1.27)
					(thickness 0.15)
				)
				(justify left)
			)
		)
		(property "Footprint" "antmicro-footprints:MP_Pad6mm_Drill3mm"
			(at 52.07 226.06 0)
			(effects
				(font
					(size 1.27 1.27)
					(thickness 0.15)
				)
				(justify left bottom)
				(hide yes)
			)
		)
		(property "Datasheet" ""
			(at 48.59 234.01 0)
			(effects
				(font
					(size 1.27 1.27)
					(thickness 0.15)
				)
				(justify left bottom)
				(hide yes)
			)
		)
		(property "Description" ""
			(at 31.75 218.44 0)
			(effects
				(font
					(size 1.27 1.27)
				)
				(hide yes)
			)
		)
		(property "Author" "Antmicro"
			(at 52.07 228.6 0)
			(effects
				(font
					(size 1.27 1.27)
					(thickness 0.15)
				)
				(justify left bottom)
				(hide yes)
			)
		)
		(property "License" "Apache-2.0"
			(at 52.07 231.14 0)
			(effects
				(font
					(size 1.27 1.27)
					(thickness 0.15)
				)
				(justify left bottom)
				(hide yes)
			)
		)
		(pin "1"
		)
		(instances
			(project "gmsl-serializer"
				(path ""
					(reference "MP1")
					(unit 1)
				)
			)
		)
	)
	(symbol
		(lib_id "antmicroMechanicalParts:MP_Pad6mm_Drill3mm")
		(at 31.75 226.06 0)
		(unit 1)
		(exclude_from_sim no)
		(in_bom no)
		(on_board yes)
		(dnp no)
		(fields_autoplaced yes)
		(property "Reference" "MP2"
			(at 40.64 224.7899 0)
			(effects
				(font
					(size 1.27 1.27)
					(thickness 0.15)
				)
				(justify left)
			)
		)
		(property "Value" "MP_Pad6mm_Drill3mm"
			(at 40.64 227.3299 0)
			(effects
				(font
					(size 1.27 1.27)
					(thickness 0.15)
				)
				(justify left)
			)
		)
		(property "Footprint" "antmicro-footprints:MP_Pad6mm_Drill3mm"
			(at 52.07 233.68 0)
			(effects
				(font
					(size 1.27 1.27)
					(thickness 0.15)
				)
				(justify left bottom)
				(hide yes)
			)
		)
		(property "Datasheet" ""
			(at 48.59 241.63 0)
			(effects
				(font
					(size 1.27 1.27)
					(thickness 0.15)
				)
				(justify left bottom)
				(hide yes)
			)
		)
		(property "Description" ""
			(at 31.75 226.06 0)
			(effects
				(font
					(size 1.27 1.27)
				)
				(hide yes)
			)
		)
		(property "Author" "Antmicro"
			(at 52.07 236.22 0)
			(effects
				(font
					(size 1.27 1.27)
					(thickness 0.15)
				)
				(justify left bottom)
				(hide yes)
			)
		)
		(property "License" "Apache-2.0"
			(at 52.07 238.76 0)
			(effects
				(font
					(size 1.27 1.27)
					(thickness 0.15)
				)
				(justify left bottom)
				(hide yes)
			)
		)
		(pin "1"
		)
		(instances
			(project "gmsl-serializer"
				(path ""
					(reference "MP2")
					(unit 1)
				)
			)
		)
	)
	(symbol
		(lib_id "antmicropower:GND")
		(at 27.94 243.84 0)
		(unit 1)
		(exclude_from_sim no)
		(in_bom yes)
		(on_board yes)
		(dnp no)
		(property "Reference" "#PWR0157"
			(at 36.83 246.38 0)
			(effects
				(font
					(size 1.27 1.27)
					(thickness 0.15)
				)
				(justify left bottom)
				(hide yes)
			)
		)
		(property "Value" "GND"
			(at 27.94 247.65 0)
			(effects
				(font
					(size 1.27 1.27)
					(thickness 0.15)
				)
			)
		)
		(property "Footprint" ""
			(at 36.83 251.46 0)
			(effects
				(font
					(size 1.27 1.27)
					(thickness 0.15)
				)
				(justify left bottom)
				(hide yes)
			)
		)
		(property "Datasheet" ""
			(at 36.83 256.54 0)
			(effects
				(font
					(size 1.27 1.27)
					(thickness 0.15)
				)
				(justify left bottom)
				(hide yes)
			)
		)
		(property "Description" ""
			(at 27.94 243.84 0)
			(effects
				(font
					(size 1.27 1.27)
				)
				(hide yes)
			)
		)
		(property "Author" "Antmicro"
			(at 36.83 251.46 0)
			(effects
				(font
					(size 1.27 1.27)
					(thickness 0.15)
				)
				(justify left bottom)
				(hide yes)
			)
		)
		(property "License" "Apache-2.0"
			(at 36.83 254 0)
			(effects
				(font
					(size 1.27 1.27)
					(thickness 0.15)
				)
				(justify left bottom)
				(hide yes)
			)
		)
		(pin "1"
		)
		(instances
			(project "gmsl-serializer"
				(path ""
					(reference "#PWR0157")
					(unit 1)
				)
			)
		)
	)
	(symbol
		(lib_id "antmicroMechanicalParts:MP_Pad6mm_Drill3mm")
		(at 31.75 232.41 0)
		(unit 1)
		(exclude_from_sim no)
		(in_bom no)
		(on_board yes)
		(dnp no)
		(fields_autoplaced yes)
		(property "Reference" "MP3"
			(at 40.64 231.1399 0)
			(effects
				(font
					(size 1.27 1.27)
					(thickness 0.15)
				)
				(justify left)
			)
		)
		(property "Value" "MP_Pad6mm_Drill3mm"
			(at 40.64 233.6799 0)
			(effects
				(font
					(size 1.27 1.27)
					(thickness 0.15)
				)
				(justify left)
			)
		)
		(property "Footprint" "antmicro-footprints:MP_Pad6mm_Drill3mm"
			(at 52.07 240.03 0)
			(effects
				(font
					(size 1.27 1.27)
					(thickness 0.15)
				)
				(justify left bottom)
				(hide yes)
			)
		)
		(property "Datasheet" ""
			(at 48.59 247.98 0)
			(effects
				(font
					(size 1.27 1.27)
					(thickness 0.15)
				)
				(justify left bottom)
				(hide yes)
			)
		)
		(property "Description" ""
			(at 31.75 232.41 0)
			(effects
				(font
					(size 1.27 1.27)
				)
				(hide yes)
			)
		)
		(property "Author" "Antmicro"
			(at 52.07 242.57 0)
			(effects
				(font
					(size 1.27 1.27)
					(thickness 0.15)
				)
				(justify left bottom)
				(hide yes)
			)
		)
		(property "License" "Apache-2.0"
			(at 52.07 245.11 0)
			(effects
				(font
					(size 1.27 1.27)
					(thickness 0.15)
				)
				(justify left bottom)
				(hide yes)
			)
		)
		(pin "1"
		)
		(instances
			(project "gmsl-serializer"
				(path ""
					(reference "MP3")
					(unit 1)
				)
			)
		)
	)
	(sheet
		(at 250.19 170.18)
		(size 24.13 16.51)
		(fields_autoplaced yes)
		(stroke
			(width 0.1524)
			(type solid)
		)
		(fill
			(color 0 0 0 0.0000)
		)
		(property "Sheetname" "GMSL Connector"
			(at 250.19 169.4684 0)
			(effects
				(font
					(size 1.27 1.27)
				)
				(justify left bottom)
			)
		)
		(property "Sheetfile" "GMSL.kicad_sch"
			(at 250.19 187.2746 0)
			(effects
				(font
					(size 1.27 1.27)
				)
				(justify left top)
			)
		)
		(pin "SIO_P" bidirectional
			(at 250.19 173.99 180)
			(effects
				(font
					(size 1.27 1.27)
				)
				(justify left)
			)
		)
		(instances
			(project "gmsl-serializer"
				(path ""
					(page "5")
				)
			)
		)
	)
	(sheet
		(at 167.64 170.18)
		(size 24.13 16.51)
		(fields_autoplaced yes)
		(stroke
			(width 0.1524)
			(type solid)
		)
		(fill
			(color 0 0 0 0.0000)
		)
		(property "Sheetname" "CSI Connector"
			(at 167.64 169.4684 0)
			(effects
				(font
					(size 1.27 1.27)
				)
				(justify left bottom)
			)
		)
		(property "Sheetfile" "CSI.kicad_sch"
			(at 167.64 187.2746 0)
			(effects
				(font
					(size 1.27 1.27)
				)
				(justify left top)
			)
		)
		(pin "CSI{CSI}" output
			(at 191.77 173.99 0)
			(effects
				(font
					(size 1.27 1.27)
				)
				(justify right)
			)
		)
		(pin "I2C{I2C}" bidirectional
			(at 191.77 176.53 0)
			(effects
				(font
					(size 1.27 1.27)
				)
				(justify right)
			)
		)
		(pin "GPIO4" input
			(at 191.77 181.61 0)
			(effects
				(font
					(size 1.27 1.27)
				)
				(justify right)
			)
		)
		(pin "GPIO3" input
			(at 191.77 179.07 0)
			(effects
				(font
					(size 1.27 1.27)
				)
				(justify right)
			)
		)
		(instances
			(project "gmsl-serializer"
				(path ""
					(page "2")
				)
			)
		)
	)
	(sheet
		(at 208.28 170.18)
		(size 24.13 16.51)
		(fields_autoplaced yes)
		(stroke
			(width 0.1524)
			(type solid)
		)
		(fill
			(color 0 0 0 0.0000)
		)
		(property "Sheetname" "Serializer"
			(at 208.28 169.4684 0)
			(effects
				(font
					(size 1.27 1.27)
				)
				(justify left bottom)
			)
		)
		(property "Sheetfile" "serializer.kicad_sch"
			(at 208.28 187.2746 0)
			(effects
				(font
					(size 1.27 1.27)
				)
				(justify left top)
			)
		)
		(pin "GPIO4" output
			(at 208.28 181.61 180)
			(effects
				(font
					(size 1.27 1.27)
				)
				(justify left)
			)
		)
		(pin "GPIO3" output
			(at 208.28 179.07 180)
			(effects
				(font
					(size 1.27 1.27)
				)
				(justify left)
			)
		)
		(pin "VREF" input
			(at 232.41 184.15 0)
			(effects
				(font
					(size 1.27 1.27)
				)
				(justify right)
			)
		)
		(pin "I2C{I2C}" bidirectional
			(at 208.28 176.53 180)
			(effects
				(font
					(size 1.27 1.27)
				)
				(justify left)
			)
		)
		(pin "SIO_P" bidirectional
			(at 232.41 173.99 0)
			(effects
				(font
					(size 1.27 1.27)
				)
				(justify right)
			)
		)
		(pin "CSI{CSI}" input
			(at 208.28 173.99 180)
			(effects
				(font
					(size 1.27 1.27)
				)
				(justify left)
			)
		)
		(instances
			(project "gmsl-serializer"
				(path ""
					(page "4")
				)
			)
		)
	)
	(sheet
		(at 208.28 198.12)
		(size 24.13 16.51)
		(fields_autoplaced yes)
		(stroke
			(width 0.1524)
			(type solid)
		)
		(fill
			(color 0 0 0 0.0000)
		)
		(property "Sheetname" "Supply"
			(at 208.28 197.4084 0)
			(effects
				(font
					(size 1.27 1.27)
				)
				(justify left bottom)
			)
		)
		(property "Sheetfile" "supply.kicad_sch"
			(at 208.28 215.2146 0)
			(effects
				(font
					(size 1.27 1.27)
				)
				(justify left top)
			)
		)
		(pin "VREF" output
			(at 232.41 200.66 0)
			(effects
				(font
					(size 1.27 1.27)
				)
				(justify right)
			)
		)
		(instances
			(project "gmsl-serializer"
				(path ""
					(page "3")
				)
			)
		)
	)
	(sheet_instances
		(path "/"
			(page "1")
		)
	)
)
